# BASEBOARD_FAB2 (Tioga Pass) — schematic netlist excerpt (pin names and nets, part order shuffled) for the footprints in the layout excerpt that follows; sources: Cadence DE-HDL packaged netlist, KiCad conversion of Wiwynn_Tioga_Pass_MB.brd

R2R7  RES  4.75K 1% CHIP  pkg 0402  page 191 : A = P3V3_STBY ; B = FM_FORCE_ADR_N
R2T67  RES  0.0 5% CHIP  pkg 0402  page 93 : A = FM_CPU0_PROCHOT_LVT3_R_N ; B = FM_CPU0_PROCHOT_LVT3_K_N
C9G2  CAP  470PF 50V 10% X7R  pkg 0402LF  page 141 : A = P3V3_STBY ; B = GND

(kicad_pcb
	(version 20260206)
	(generator "pcbnew")
	(generator_version "10.0")
	(general
		(thickness 1.6)
		(legacy_teardrops no)
	)
	(paper "A4")
	(title_block
		(title "Wiwynn_Tioga_Pass_MB.brd")
		(comment 1 "Tioga Pass / footprints 3759-3761 of 4770")
	)
	(layers
		(0 "F.Cu" signal "TOP")
		(4 "In1.Cu" signal "L2GND")
		(6 "In2.Cu" signal "L3")
		(8 "In3.Cu" signal "L4GND")
		(10 "In4.Cu" signal "L5")
		(12 "In5.Cu" signal "L6GND")
		(14 "In6.Cu" signal "L7VCC")
		(16 "In7.Cu" signal "L8VCC")
		(18 "In8.Cu" signal "L9GND")
		(20 "In9.Cu" signal "L10")
		(22 "In10.Cu" signal "L11GND")
		(24 "In11.Cu" signal "L12")
		(26 "In12.Cu" signal "L13GND")
		(2 "B.Cu" signal "BOTTOM")
		(9 "F.Adhes" user "F.Adhesive")
		(11 "B.Adhes" user "B.Adhesive")
		(13 "F.Paste" user "Package Geometry/Pastemask Top")
		(15 "B.Paste" user "Package Geometry/Pastemask Bottom")
		(5 "F.SilkS" user "Ref Des/Silkscreen Top")
		(7 "B.SilkS" user "Ref Des/Silkscreen Bottom")
		(1 "F.Mask" user "Board Geometry/Soldermask Top")
		(3 "B.Mask" user "Board Geometry/Soldermask Bottom")
		(17 "Dwgs.User" user "User.Drawings")
		(19 "Cmts.User" user "User.Comments")
		(21 "Eco1.User" user "User.Eco1")
		(23 "Eco2.User" user "User.Eco2")
		(25 "Edge.Cuts" user "Board Geometry/Outline")
		(27 "Margin" user)
		(31 "F.CrtYd" user "Package Geometry/Place Bound Top")
		(29 "B.CrtYd" user "Package Geometry/Place Bound Bottom")
		(35 "F.Fab" user "Ref Des/Assembly Top")
		(33 "B.Fab" user "Ref Des/Assembly Bottom")
	)
	(footprint ""
		(layer "B.Cu")
		(at 362.270294 -45.671486)
		(property "Reference" "R2T67"
			(at 0 0 0)
			(layer "B.SilkS")
			(hide yes)
			(effects
				(font
					(size 1.27 1.27)
				)
				(justify mirror)
			)
		)
		(property "Value" ""
			(at 0 0 0)
			(layer "B.Fab")
			(effects
				(font
					(size 1.27 1.27)
				)
				(justify mirror)
			)
		)
		(duplicate_pad_numbers_are_jumpers no)
		(fp_poly
			(pts
				(xy 0.2794 -0.1016) (xy -0.2794 -0.1016) (xy -0.2794 0.9906) (xy 0.2794 0.9906)
			)
			(stroke
				(width 0)
				(type default)
			)
			(fill no)
			(layer "B.CrtYd")
		)
		(fp_line
			(start -0.2794 -0.1016)
			(end 0.2794 -0.1016)
			(stroke
				(width 0.1)
				(type default)
			)
			(layer "B.Fab")
		)
		(fp_line
			(start -0.2794 0.9906)
			(end -0.2794 -0.1016)
			(stroke
				(width 0.1)
				(type default)
			)
			(layer "B.Fab")
		)
		(fp_line
			(start 0.2794 -0.1016)
			(end 0.2794 0.9906)
			(stroke
				(width 0.1)
				(type default)
			)
			(layer "B.Fab")
		)
		(fp_line
			(start 0.2794 0.9906)
			(end -0.2794 0.9906)
			(stroke
				(width 0.1)
				(type default)
			)
			(layer "B.Fab")
		)
		(pad "1" smd rect
			(at 0 0 180)
			(size 0.508 0.508)
			(layers "B.Cu" "B.Mask" "B.Paste")
			(net "FM_CPU0_PROCHOT_LVT3_R_N")
		)
		(pad "2" smd rect
			(at 0 0.889 180)
			(size 0.508 0.508)
			(layers "B.Cu" "B.Mask" "B.Paste")
			(net "FM_CPU0_PROCHOT_LVT3_K_N")
		)
		(zone
			(layer "B.Cu")
			(hatch none 0.5)
			(connect_pads
				(clearance 0)
			)
			(min_thickness 0.25)
			(keepout
				(tracks allowed)
				(vias not_allowed)
				(pads allowed)
				(copperpour not_allowed)
				(footprints allowed)
			)
			(placement
				(enabled no)
				(sheetname "")
			)
			(fill
				(thermal_gap 0.5)
				(thermal_bridge_width 0.5)
				(island_removal_mode 0)
			)
			(polygon
				(pts
					(xy 362.524294 -45.417486) (xy 362.016294 -45.417486) (xy 362.016294 -45.036486) (xy 362.524294 -45.036486)
				)
			)
		)
		(zone
			(layer "B.Cu")
			(hatch none 0.5)
			(connect_pads
				(clearance 0)
			)
			(min_thickness 0.25)
			(keepout
				(tracks not_allowed)
				(vias allowed)
				(pads allowed)
				(copperpour not_allowed)
				(footprints allowed)
			)
			(placement
				(enabled no)
				(sheetname "")
			)
			(fill
				(thermal_gap 0.5)
				(thermal_bridge_width 0.5)
				(island_removal_mode 0)
			)
			(polygon
				(pts
					(xy 362.524294 -45.036486) (xy 362.016294 -45.036486) (xy 362.016294 -45.417486) (xy 362.524294 -45.417486)
				)
			)
		)
	)
	(footprint ""
		(layer "B.Cu")
		(at 375.412 -66.04 180)
		(property "Reference" "R2R7"
			(at 0 0 0)
			(layer "B.SilkS")
			(hide yes)
			(effects
				(font
					(size 1.27 1.27)
				)
				(justify mirror)
			)
		)
		(property "Value" ""
			(at 0 0 0)
			(layer "B.Fab")
			(effects
				(font
					(size 1.27 1.27)
				)
				(justify mirror)
			)
		)
		(duplicate_pad_numbers_are_jumpers no)
		(fp_poly
			(pts
				(xy 0.2794 -0.1016) (xy -0.2794 -0.1016) (xy -0.2794 0.9906) (xy 0.2794 0.9906)
			)
			(stroke
				(width 0)
				(type default)
			)
			(fill no)
			(layer "B.CrtYd")
		)
		(fp_line
			(start 0.2794 0.9906)
			(end -0.2794 0.9906)
			(stroke
				(width 0.1)
				(type default)
			)
			(layer "B.Fab")
		)
		(fp_line
			(start 0.2794 -0.1016)
			(end 0.2794 0.9906)
			(stroke
				(width 0.1)
				(type default)
			)
			(layer "B.Fab")
		)
		(fp_line
			(start -0.2794 0.9906)
			(end -0.2794 -0.1016)
			(stroke
				(width 0.1)
				(type default)
			)
			(layer "B.Fab")
		)
		(fp_line
			(start -0.2794 -0.1016)
			(end 0.2794 -0.1016)
			(stroke
				(width 0.1)
				(type default)
			)
			(layer "B.Fab")
		)
		(pad "1" smd rect
			(at 0 0)
			(size 0.508 0.508)
			(layers "B.Cu" "B.Mask" "B.Paste")
			(net "P3V3_STBY")
		)
		(pad "2" smd rect
			(at 0 0.889)
			(size 0.508 0.508)
			(layers "B.Cu" "B.Mask" "B.Paste")
			(net "FM_FORCE_ADR_N")
		)
		(zone
			(layer "B.Cu")
			(hatch none 0.5)
			(connect_pads
				(clearance 0)
			)
			(min_thickness 0.25)
			(keepout
				(tracks not_allowed)
				(vias allowed)
				(pads allowed)
				(copperpour not_allowed)
				(footprints allowed)
			)
			(placement
				(enabled no)
				(sheetname "")
			)
			(fill
				(thermal_gap 0.5)
				(thermal_bridge_width 0.5)
				(island_removal_mode 0)
			)
			(polygon
				(pts
					(xy 375.158 -66.675) (xy 375.666 -66.675) (xy 375.666 -66.294) (xy 375.158 -66.294)
				)
			)
		)
		(zone
			(layer "B.Cu")
			(hatch none 0.5)
			(connect_pads
				(clearance 0)
			)
			(min_thickness 0.25)
			(keepout
				(tracks allowed)
				(vias not_allowed)
				(pads allowed)
				(copperpour not_allowed)
				(footprints allowed)
			)
			(placement
				(enabled no)
				(sheetname "")
			)
			(fill
				(thermal_gap 0.5)
				(thermal_bridge_width 0.5)
				(island_removal_mode 0)
			)
			(polygon
				(pts
					(xy 375.158 -66.294) (xy 375.666 -66.294) (xy 375.666 -66.675) (xy 375.158 -66.675)
				)
			)
		)
	)
	(footprint ""
		(layer "B.Cu")
		(at 485.942894 4.157472 -90)
		(property "Reference" "C9G2"
			(at 0 0 90)
			(layer "B.SilkS")
			(hide yes)
			(effects
				(font
					(size 1.27 1.27)
				)
				(justify mirror)
			)
		)
		(property "Value" ""
			(at 0 0 90)
			(layer "B.Fab")
			(effects
				(font
					(size 1.27 1.27)
				)
				(justify mirror)
			)
		)
		(duplicate_pad_numbers_are_jumpers no)
		(fp_poly
			(pts
				(xy -0.3048 -0.1016) (xy -0.3048 0.9906) (xy 0.3048 0.9906) (xy 0.3048 -0.1016)
			)
			(stroke
				(width 0)
				(type default)
			)
			(fill no)
			(layer "B.CrtYd")
		)
		(fp_line
			(start -0.3048 0.9906)
			(end -0.3048 -0.1016)
			(stroke
				(width 0.1)
				(type default)
			)
			(layer "B.Fab")
		)
		(fp_line
			(start 0.3048 0.9906)
			(end -0.3048 0.9906)
			(stroke
				(width 0.1)
				(type default)
			)
			(layer "B.Fab")
		)
		(fp_line
			(start -0.3048 -0.1016)
			(end 0.3048 -0.1016)
			(stroke
				(width 0.1)
				(type default)
			)
			(layer "B.Fab")
		)
		(fp_line
			(start 0.3048 -0.1016)
			(end 0.3048 0.9906)
			(stroke
				(width 0.1)
				(type default)
			)
			(layer "B.Fab")
		)
		(pad "1" smd rect
			(at 0 0 90)
			(size 0.508 0.508)
			(layers "B.Cu" "B.Mask" "B.Paste")
			(net "P3V3_STBY")
		)
		(pad "2" smd rect
			(at 0 0.889 90)
			(size 0.508 0.508)
			(layers "B.Cu" "B.Mask" "B.Paste")
			(net "GND")
		)
		(zone
			(layer "B.Cu")
			(hatch none 0.5)
			(connect_pads
				(clearance 0)
			)
			(min_thickness 0.25)
			(keepout
				(tracks not_allowed)
				(vias allowed)
				(pads allowed)
				(copperpour not_allowed)
				(footprints allowed)
			)
			(placement
				(enabled no)
				(sheetname "")
			)
			(fill
				(thermal_gap 0.5)
				(thermal_bridge_width 0.5)
				(island_removal_mode 0)
			)
			(polygon
				(pts
					(xy 485.307894 4.411472) (xy 485.307894 3.903472) (xy 485.688894 3.903472) (xy 485.688894 4.411472)
				)
			)
		)
		(zone
			(layer "B.Cu")
			(hatch none 0.5)
			(connect_pads
				(clearance 0)
			)
			(min_thickness 0.25)
			(keepout
				(tracks allowed)
				(vias not_allowed)
				(pads allowed)
				(copperpour not_allowed)
				(footprints allowed)
			)
			(placement
				(enabled no)
				(sheetname "")
			)
			(fill
				(thermal_gap 0.5)
				(thermal_bridge_width 0.5)
				(island_removal_mode 0)
			)
			(polygon
				(pts
					(xy 485.688894 4.411472) (xy 485.688894 3.903472) (xy 485.307894 3.903472) (xy 485.307894 4.411472)
				)
			)
		)
	)
)
